# BASEBOARD_FAB2 (Tioga Pass) — schematic netlist excerpt (pin names and nets, part order shuffled) for the footprints in the layout excerpt that follows; sources: Cadence DE-HDL packaged netlist, KiCad conversion of Wiwynn_Tioga_Pass_MB.brd

L1E1  IND-120NH-30-GP  pkg DISCRET-GB2  page 207 : S = VR_PVCCIN_CPU1_PHASE1 ; F = PVCCIN_CPU1
T1P26  TPAD-SE-2P-GP  pkg DISCRET-GA1  page 256 : \1\ = L3_40OHM_6INCH ; GND1 = GND
R4D7  RES  27.4 1% CHIP  pkg 0402  page 103 : A = CLK_100M_CPU0_RC_REFCLK0_R_DN ; B = CLK_100M_CPU0_RC_REFCLK0_DN

(kicad_pcb
	(version 20260206)
	(generator "pcbnew")
	(generator_version "10.0")
	(general
		(thickness 1.6)
		(legacy_teardrops no)
	)
	(paper "A4")
	(title_block
		(title "Wiwynn_Tioga_Pass_MB.brd")
		(comment 1 "Tioga Pass / footprints 910-912 of 4770")
	)
	(layers
		(0 "F.Cu" signal "TOP")
		(4 "In1.Cu" signal "L2GND")
		(6 "In2.Cu" signal "L3")
		(8 "In3.Cu" signal "L4GND")
		(10 "In4.Cu" signal "L5")
		(12 "In5.Cu" signal "L6GND")
		(14 "In6.Cu" signal "L7VCC")
		(16 "In7.Cu" signal "L8VCC")
		(18 "In8.Cu" signal "L9GND")
		(20 "In9.Cu" signal "L10")
		(22 "In10.Cu" signal "L11GND")
		(24 "In11.Cu" signal "L12")
		(26 "In12.Cu" signal "L13GND")
		(2 "B.Cu" signal "BOTTOM")
		(9 "F.Adhes" user "F.Adhesive")
		(11 "B.Adhes" user "B.Adhesive")
		(13 "F.Paste" user "Package Geometry/Pastemask Top")
		(15 "B.Paste" user "Package Geometry/Pastemask Bottom")
		(5 "F.SilkS" user "Ref Des/Silkscreen Top")
		(7 "B.SilkS" user "Ref Des/Silkscreen Bottom")
		(1 "F.Mask" user "Board Geometry/Soldermask Top")
		(3 "B.Mask" user "Board Geometry/Soldermask Bottom")
		(17 "Dwgs.User" user "User.Drawings")
		(19 "Cmts.User" user "User.Comments")
		(21 "Eco1.User" user "User.Eco1")
		(23 "Eco2.User" user "User.Eco2")
		(25 "Edge.Cuts" user "Board Geometry/Outline")
		(27 "Margin" user)
		(31 "F.CrtYd" user "Package Geometry/Place Bound Top")
		(29 "B.CrtYd" user "Package Geometry/Place Bound Bottom")
		(35 "F.Fab" user "Ref Des/Assembly Top")
		(33 "B.Fab" user "Ref Des/Assembly Bottom")
	)
	(footprint ""
		(layer "F.Cu")
		(at 14.097 10.7315 -90)
		(property "Reference" "T1P26"
			(at 0 0 270)
			(layer "F.SilkS")
			(hide yes)
			(effects
				(font
					(size 1.27 1.27)
				)
			)
		)
		(property "Value" "*"
			(at 0 -3.44805 270)
			(unlocked yes)
			(layer "F.Fab")
			(hide yes)
			(effects
				(font
					(size 0.889 0.889)
					(thickness 0.1524)
				)
			)
		)
		(property "Device Type" "TPAD-SE-2P-GP_DISCRET-GA1-TPADA"
			(at 0 -4.97205 270)
			(unlocked yes)
			(layer "F.Fab")
			(hide yes)
			(effects
				(font
					(size 0.889 0.889)
					(thickness 0.1524)
				)
			)
		)
		(duplicate_pad_numbers_are_jumpers no)
		(fp_line
			(start -1.016 2.286)
			(end -1.016 -2.286)
			(stroke
				(width 0.1524)
				(type default)
			)
			(layer "F.SilkS")
		)
		(fp_line
			(start 1.016 2.286)
			(end -1.016 2.286)
			(stroke
				(width 0.1524)
				(type default)
			)
			(layer "F.SilkS")
		)
		(fp_line
			(start -1.016 -2.286)
			(end 1.016 -2.286)
			(stroke
				(width 0.1524)
				(type default)
			)
			(layer "F.SilkS")
		)
		(fp_line
			(start 1.016 -2.286)
			(end 1.016 2.286)
			(stroke
				(width 0.1524)
				(type default)
			)
			(layer "F.SilkS")
		)
		(fp_rect
			(start -1.27 2.54)
			(end 1.27 -2.54)
			(stroke
				(width 0)
				(type default)
			)
			(fill no)
			(layer "F.CrtYd")
		)
		(fp_rect
			(start -1.27 2.54)
			(end 1.27 -2.54)
			(stroke
				(width 0)
				(type default)
			)
			(fill no)
			(layer "F.Fab")
		)
		(pad "1" thru_hole circle
			(at 0 -1.27 270)
			(size 1.524 1.524)
			(drill 0.9144)
			(layers "*.Cu" "*.Mask")
			(remove_unused_layers no)
			(net "L3_40OHM_6INCH")
			(clearance -0.0508)
			(thermal_gap 0.127)
			(padstack
				(mode front_inner_back)
				(layer "Inner"
					(shape circle)
					(size 1.1684 1.1684)
					(clearance 0.127)
				)
				(layer "B.Cu"
					(shape circle)
					(size 1.524 1.524)
					(clearance -0.0508)
				)
			)
		)
		(pad "GND1" thru_hole rect
			(at 0 1.27 270)
			(size 1.524 1.524)
			(drill 0.9144)
			(layers "*.Cu" "*.Mask")
			(remove_unused_layers no)
			(net "GND")
			(clearance -0.0508)
			(thermal_gap 0.127)
			(padstack
				(mode front_inner_back)
				(layer "Inner"
					(shape circle)
					(size 1.1684 1.1684)
					(clearance 0.127)
				)
				(layer "B.Cu"
					(shape rect)
					(size 1.524 1.524)
					(clearance -0.0508)
				)
			)
		)
	)
	(footprint ""
		(layer "F.Cu")
		(at 40.036496 -57.031382)
		(property "Reference" "L1E1"
			(at 3.378708 -4.251706 0)
			(unlocked yes)
			(layer "F.SilkS")
			(effects
				(font
					(size 0.4064 0.254)
					(thickness 0.1524)
				)
			)
		)
		(property "Value" ""
			(at 0 0 0)
			(layer "F.Fab")
			(effects
				(font
					(size 1.27 1.27)
				)
			)
		)
		(duplicate_pad_numbers_are_jumpers no)
		(fp_line
			(start -1.1303 -3.199892)
			(end 8.3693 -3.199892)
			(stroke
				(width 0.1524)
				(type default)
			)
			(layer "F.SilkS")
		)
		(fp_line
			(start -1.1303 -1.6637)
			(end -1.1303 -3.199892)
			(stroke
				(width 0.1524)
				(type default)
			)
			(layer "F.SilkS")
		)
		(fp_line
			(start -1.1303 3.199892)
			(end -1.1303 1.6637)
			(stroke
				(width 0.1524)
				(type default)
			)
			(layer "F.SilkS")
		)
		(fp_line
			(start 8.3693 -3.199892)
			(end 8.3693 -1.6637)
			(stroke
				(width 0.1524)
				(type default)
			)
			(layer "F.SilkS")
		)
		(fp_line
			(start 8.3693 1.6637)
			(end 8.3693 3.199892)
			(stroke
				(width 0.1524)
				(type default)
			)
			(layer "F.SilkS")
		)
		(fp_line
			(start 8.3693 3.199892)
			(end -1.1303 3.199892)
			(stroke
				(width 0.1524)
				(type default)
			)
			(layer "F.SilkS")
		)
		(fp_rect
			(start -1.1303 3.199892)
			(end 8.3693 -3.199892)
			(stroke
				(width 0)
				(type default)
			)
			(fill no)
			(layer "F.CrtYd")
		)
		(fp_line
			(start -1.1303 -3.199892)
			(end 8.3693 -3.199892)
			(stroke
				(width 0.1)
				(type default)
			)
			(layer "F.Fab")
		)
		(fp_line
			(start -1.1303 3.199892)
			(end -1.1303 -3.199892)
			(stroke
				(width 0.1)
				(type default)
			)
			(layer "F.Fab")
		)
		(fp_line
			(start 8.3693 -3.199892)
			(end 8.3693 3.199892)
			(stroke
				(width 0.1)
				(type default)
			)
			(layer "F.Fab")
		)
		(fp_line
			(start 8.3693 3.199892)
			(end -1.1303 3.199892)
			(stroke
				(width 0.1)
				(type default)
			)
			(layer "F.Fab")
		)
		(pad "1" smd rect
			(at 0 0)
			(size 3.683 2.667)
			(layers "F.Cu" "F.Mask" "F.Paste")
			(net "VR_PVCCIN_CPU1_PHASE1")
		)
		(pad "2" smd rect
			(at 7.239 0)
			(size 3.683 2.667)
			(layers "F.Cu" "F.Mask" "F.Paste")
			(net "PVCCIN_CPU1")
		)
	)
	(footprint ""
		(layer "F.Cu")
		(at 172.466 -86.868 180)
		(property "Reference" "R4D7"
			(at 0 0 180)
			(layer "F.SilkS")
			(hide yes)
			(effects
				(font
					(size 1.27 1.27)
				)
			)
		)
		(property "Value" ""
			(at 0 0 180)
			(layer "F.Fab")
			(effects
				(font
					(size 1.27 1.27)
				)
			)
		)
		(duplicate_pad_numbers_are_jumpers no)
		(fp_poly
			(pts
				(xy -0.2794 -0.1016) (xy 0.2794 -0.1016) (xy 0.2794 0.9906) (xy -0.2794 0.9906)
			)
			(stroke
				(width 0)
				(type default)
			)
			(fill no)
			(layer "F.CrtYd")
		)
		(fp_line
			(start 0.2794 0.9906)
			(end 0.2794 -0.1016)
			(stroke
				(width 0.1)
				(type default)
			)
			(layer "F.Fab")
		)
		(fp_line
			(start 0.2794 -0.1016)
			(end -0.2794 -0.1016)
			(stroke
				(width 0.1)
				(type default)
			)
			(layer "F.Fab")
		)
		(fp_line
			(start -0.2794 0.9906)
			(end 0.2794 0.9906)
			(stroke
				(width 0.1)
				(type default)
			)
			(layer "F.Fab")
		)
		(fp_line
			(start -0.2794 -0.1016)
			(end -0.2794 0.9906)
			(stroke
				(width 0.1)
				(type default)
			)
			(layer "F.Fab")
		)
		(pad "1" smd rect
			(at 0 0 180)
			(size 0.508 0.508)
			(layers "F.Cu" "F.Mask" "F.Paste")
			(net "CLK_100M_CPU0_RC_REFCLK0_R_DN")
		)
		(pad "2" smd rect
			(at 0 0.889 180)
			(size 0.508 0.508)
			(layers "F.Cu" "F.Mask" "F.Paste")
			(net "CLK_100M_CPU0_RC_REFCLK0_DN")
		)
		(zone
			(layer "F.Cu")
			(hatch none 0.5)
			(connect_pads
				(clearance 0)
			)
			(min_thickness 0.25)
			(keepout
				(tracks not_allowed)
				(vias allowed)
				(pads allowed)
				(copperpour not_allowed)
				(footprints allowed)
			)
			(placement
				(enabled no)
				(sheetname "")
			)
			(fill
				(thermal_gap 0.5)
				(thermal_bridge_width 0.5)
				(island_removal_mode 0)
			)
			(polygon
				(pts
					(xy 172.72 -87.503) (xy 172.212 -87.503) (xy 172.212 -87.122) (xy 172.72 -87.122)
				)
			)
		)
		(zone
			(layer "F.Cu")
			(hatch none 0.5)
			(connect_pads
				(clearance 0)
			)
			(min_thickness 0.25)
			(keepout
				(tracks allowed)
				(vias not_allowed)
				(pads allowed)
				(copperpour not_allowed)
				(footprints allowed)
			)
			(placement
				(enabled no)
				(sheetname "")
			)
			(fill
				(thermal_gap 0.5)
				(thermal_bridge_width 0.5)
				(island_removal_mode 0)
			)
			(polygon
				(pts
					(xy 172.72 -87.122) (xy 172.212 -87.122) (xy 172.212 -87.503) (xy 172.72 -87.503)
				)
			)
		)
	)
)
